(kicad_pcb
	(version 20260206)
	(generator "pcbnew")
	(generator_version "10.0")
	(general
		(thickness 1.6)
		(legacy_teardrops no)
	)
	(paper "A4")
	(title_block
		(title "12092022_DA0F0TMDCD0_F0T_Management_Board_D_brd_V3_OCP.brd")
		(comment 1 "Grand Teton / footprints 1111-1116 of 1440")
	)
	(layers
		(0 "F.Cu" signal "TOP")
		(4 "In1.Cu" signal "GND")
		(6 "In2.Cu" signal "IN1")
		(8 "In3.Cu" signal "GND1")
		(10 "In4.Cu" signal "IN2")
		(12 "In5.Cu" signal "VCC")
		(14 "In6.Cu" signal "VCC1")
		(16 "In7.Cu" signal "IN3")
		(18 "In8.Cu" signal "GND2")
		(20 "In9.Cu" signal "IN4")
		(22 "In10.Cu" signal "GND3")
		(2 "B.Cu" signal "BOTTOM")
		(9 "F.Adhes" user "F.Adhesive")
		(11 "B.Adhes" user "B.Adhesive")
		(13 "F.Paste" user "Package Geometry/Pastemask Top")
		(15 "B.Paste" user "Package Geometry/Pastemask Bottom")
		(5 "F.SilkS" user "Ref Des/Silkscreen Top")
		(7 "B.SilkS" user "Ref Des/Silkscreen Bottom")
		(1 "F.Mask" user "Board Geometry/Soldermask Top")
		(3 "B.Mask" user "Board Geometry/Soldermask Bottom")
		(17 "Dwgs.User" user "User.Drawings")
		(19 "Cmts.User" user "User.Comments")
		(21 "Eco1.User" user "User.Eco1")
		(23 "Eco2.User" user "User.Eco2")
		(25 "Edge.Cuts" user "Board Geometry/Outline")
		(27 "Margin" user)
		(31 "F.CrtYd" user "Package Geometry/Place Bound Top")
		(29 "B.CrtYd" user "Package Geometry/Place Bound Bottom")
		(35 "F.Fab" user "Ref Des/Assembly Top")
		(33 "B.Fab" user "Ref Des/Assembly Bottom")
	)
	(footprint ""
		(layer "B.Cu")
		(at 11.303 -54.356 90)
		(property "Reference" "C150"
			(at 0 0 90)
			(layer "B.SilkS")
			(hide yes)
			(effects
				(font
					(size 1.27 1.27)
				)
				(justify mirror)
			)
		)
		(property "Value" ""
			(at 0 0 90)
			(layer "B.Fab")
			(effects
				(font
					(size 1.27 1.27)
				)
				(justify mirror)
			)
		)
		(duplicate_pad_numbers_are_jumpers no)
		(fp_line
			(start 0.7874 -0.4064)
			(end -0.7874 -0.4064)
			(stroke
				(width 0.1524)
				(type default)
			)
			(layer "B.SilkS")
		)
		(fp_line
			(start -0.7874 -0.4064)
			(end -0.7874 0.4064)
			(stroke
				(width 0.1524)
				(type default)
			)
			(layer "B.SilkS")
		)
		(fp_line
			(start 0.7874 0.4064)
			(end 0.7874 -0.4064)
			(stroke
				(width 0.1524)
				(type default)
			)
			(layer "B.SilkS")
		)
		(fp_line
			(start -0.7874 0.4064)
			(end 0.7874 0.4064)
			(stroke
				(width 0.1524)
				(type default)
			)
			(layer "B.SilkS")
		)
		(fp_line
			(start 0.67945 -0.305054)
			(end 0.12065 -0.305054)
			(stroke
				(width 0.1)
				(type default)
			)
			(layer "B.Fab")
		)
		(fp_line
			(start 0.12065 -0.305054)
			(end 0.12065 -0.2794)
			(stroke
				(width 0.1)
				(type default)
			)
			(layer "B.Fab")
		)
		(fp_line
			(start -0.12065 -0.3048)
			(end -0.67945 -0.3048)
			(stroke
				(width 0.1)
				(type default)
			)
			(layer "B.Fab")
		)
		(fp_line
			(start -0.67945 -0.3048)
			(end -0.67945 0.3048)
			(stroke
				(width 0.1)
				(type default)
			)
			(layer "B.Fab")
		)
		(fp_line
			(start 0.12065 -0.2794)
			(end -0.12065 -0.2794)
			(stroke
				(width 0.1)
				(type default)
			)
			(layer "B.Fab")
		)
		(fp_line
			(start -0.12065 -0.2794)
			(end -0.12065 -0.3048)
			(stroke
				(width 0.1)
				(type default)
			)
			(layer "B.Fab")
		)
		(fp_line
			(start 0.12065 0.2794)
			(end 0.12065 0.3048)
			(stroke
				(width 0.1)
				(type default)
			)
			(layer "B.Fab")
		)
		(fp_line
			(start -0.120396 0.2794)
			(end 0.12065 0.2794)
			(stroke
				(width 0.1)
				(type default)
			)
			(layer "B.Fab")
		)
		(fp_line
			(start 0.67945 0.3048)
			(end 0.67945 -0.305054)
			(stroke
				(width 0.1)
				(type default)
			)
			(layer "B.Fab")
		)
		(fp_line
			(start 0.12065 0.3048)
			(end 0.67945 0.3048)
			(stroke
				(width 0.1)
				(type default)
			)
			(layer "B.Fab")
		)
		(fp_line
			(start -0.120396 0.3048)
			(end -0.120396 0.2794)
			(stroke
				(width 0.1)
				(type default)
			)
			(layer "B.Fab")
		)
		(fp_line
			(start -0.67945 0.3048)
			(end -0.120396 0.3048)
			(stroke
				(width 0.1)
				(type default)
			)
			(layer "B.Fab")
		)
		(pad "1" smd circle
			(at 0.40005 0 270)
			(size 0 0)
			(layers "B.Cu" "B.Mask" "B.Paste")
			(net "PWRGD_P5V_AUX_R")
		)
		(pad "2" smd circle
			(at -0.40005 0 270)
			(size 0 0)
			(layers "B.Cu" "B.Mask" "B.Paste")
			(net "GND")
		)
	)
	(footprint ""
		(layer "B.Cu")
		(at 34.4424 -49.6824)
		(property "Reference" "R398"
			(at 0 0 0)
			(layer "B.SilkS")
			(hide yes)
			(effects
				(font
					(size 1.27 1.27)
				)
				(justify mirror)
			)
		)
		(property "Value" ""
			(at 0 0 0)
			(layer "B.Fab")
			(effects
				(font
					(size 1.27 1.27)
				)
				(justify mirror)
			)
		)
		(duplicate_pad_numbers_are_jumpers no)
		(fp_line
			(start -0.7874 -0.4064)
			(end -0.7874 0.4064)
			(stroke
				(width 0.1524)
				(type default)
			)
			(layer "B.SilkS")
		)
		(fp_line
			(start -0.7874 0.4064)
			(end 0.7874 0.4064)
			(stroke
				(width 0.1524)
				(type default)
			)
			(layer "B.SilkS")
		)
		(fp_line
			(start 0.7874 -0.4064)
			(end -0.7874 -0.4064)
			(stroke
				(width 0.1524)
				(type default)
			)
			(layer "B.SilkS")
		)
		(fp_line
			(start 0.7874 0.4064)
			(end 0.7874 -0.4064)
			(stroke
				(width 0.1524)
				(type default)
			)
			(layer "B.SilkS")
		)
		(fp_line
			(start -0.67945 -0.3048)
			(end -0.67945 0.3048)
			(stroke
				(width 0.1)
				(type default)
			)
			(layer "B.Fab")
		)
		(fp_line
			(start -0.67945 0.3048)
			(end -0.120396 0.3048)
			(stroke
				(width 0.1)
				(type default)
			)
			(layer "B.Fab")
		)
		(fp_line
			(start -0.12065 -0.3048)
			(end -0.67945 -0.3048)
			(stroke
				(width 0.1)
				(type default)
			)
			(layer "B.Fab")
		)
		(fp_line
			(start -0.12065 -0.2794)
			(end -0.12065 -0.3048)
			(stroke
				(width 0.1)
				(type default)
			)
			(layer "B.Fab")
		)
		(fp_line
			(start -0.120396 0.2794)
			(end 0.12065 0.2794)
			(stroke
				(width 0.1)
				(type default)
			)
			(layer "B.Fab")
		)
		(fp_line
			(start -0.120396 0.3048)
			(end -0.120396 0.2794)
			(stroke
				(width 0.1)
				(type default)
			)
			(layer "B.Fab")
		)
		(fp_line
			(start 0.12065 -0.305054)
			(end 0.12065 -0.2794)
			(stroke
				(width 0.1)
				(type default)
			)
			(layer "B.Fab")
		)
		(fp_line
			(start 0.12065 -0.2794)
			(end -0.12065 -0.2794)
			(stroke
				(width 0.1)
				(type default)
			)
			(layer "B.Fab")
		)
		(fp_line
			(start 0.12065 0.2794)
			(end 0.12065 0.3048)
			(stroke
				(width 0.1)
				(type default)
			)
			(layer "B.Fab")
		)
		(fp_line
			(start 0.12065 0.3048)
			(end 0.67945 0.3048)
			(stroke
				(width 0.1)
				(type default)
			)
			(layer "B.Fab")
		)
		(fp_line
			(start 0.67945 -0.305054)
			(end 0.12065 -0.305054)
			(stroke
				(width 0.1)
				(type default)
			)
			(layer "B.Fab")
		)
		(fp_line
			(start 0.67945 0.3048)
			(end 0.67945 -0.305054)
			(stroke
				(width 0.1)
				(type default)
			)
			(layer "B.Fab")
		)
		(pad "1" smd circle
			(at 0.40005 0 180)
			(size 0 0)
			(layers "B.Cu" "B.Mask" "B.Paste")
			(net "JTAG_1_BMC_TDO")
		)
		(pad "2" smd circle
			(at -0.40005 0 180)
			(size 0 0)
			(layers "B.Cu" "B.Mask" "B.Paste")
			(net "JTAG_1_BMC_TDO_R")
		)
	)
	(footprint ""
		(layer "B.Cu")
		(at 51.2445 -87.8205 180)
		(property "Reference" "R719"
			(at 0 0 0)
			(layer "B.SilkS")
			(hide yes)
			(effects
				(font
					(size 1.27 1.27)
				)
				(justify mirror)
			)
		)
		(property "Value" ""
			(at 0 0 0)
			(layer "B.Fab")
			(effects
				(font
					(size 1.27 1.27)
				)
				(justify mirror)
			)
		)
		(duplicate_pad_numbers_are_jumpers no)
		(fp_line
			(start 0.7874 0.4064)
			(end 0.7874 -0.4064)
			(stroke
				(width 0.1524)
				(type default)
			)
			(layer "B.SilkS")
		)
		(fp_line
			(start 0.7874 -0.4064)
			(end -0.7874 -0.4064)
			(stroke
				(width 0.1524)
				(type default)
			)
			(layer "B.SilkS")
		)
		(fp_line
			(start -0.7874 0.4064)
			(end 0.7874 0.4064)
			(stroke
				(width 0.1524)
				(type default)
			)
			(layer "B.SilkS")
		)
		(fp_line
			(start -0.7874 -0.4064)
			(end -0.7874 0.4064)
			(stroke
				(width 0.1524)
				(type default)
			)
			(layer "B.SilkS")
		)
		(fp_line
			(start 0.67945 0.3048)
			(end 0.67945 -0.305054)
			(stroke
				(width 0.1)
				(type default)
			)
			(layer "B.Fab")
		)
		(fp_line
			(start 0.67945 -0.305054)
			(end 0.12065 -0.305054)
			(stroke
				(width 0.1)
				(type default)
			)
			(layer "B.Fab")
		)
		(fp_line
			(start 0.12065 0.3048)
			(end 0.67945 0.3048)
			(stroke
				(width 0.1)
				(type default)
			)
			(layer "B.Fab")
		)
		(fp_line
			(start 0.12065 0.2794)
			(end 0.12065 0.3048)
			(stroke
				(width 0.1)
				(type default)
			)
			(layer "B.Fab")
		)
		(fp_line
			(start 0.12065 -0.2794)
			(end -0.12065 -0.2794)
			(stroke
				(width 0.1)
				(type default)
			)
			(layer "B.Fab")
		)
		(fp_line
			(start 0.12065 -0.305054)
			(end 0.12065 -0.2794)
			(stroke
				(width 0.1)
				(type default)
			)
			(layer "B.Fab")
		)
		(fp_line
			(start -0.120396 0.3048)
			(end -0.120396 0.2794)
			(stroke
				(width 0.1)
				(type default)
			)
			(layer "B.Fab")
		)
		(fp_line
			(start -0.120396 0.2794)
			(end 0.12065 0.2794)
			(stroke
				(width 0.1)
				(type default)
			)
			(layer "B.Fab")
		)
		(fp_line
			(start -0.12065 -0.2794)
			(end -0.12065 -0.3048)
			(stroke
				(width 0.1)
				(type default)
			)
			(layer "B.Fab")
		)
		(fp_line
			(start -0.12065 -0.3048)
			(end -0.67945 -0.3048)
			(stroke
				(width 0.1)
				(type default)
			)
			(layer "B.Fab")
		)
		(fp_line
			(start -0.67945 0.3048)
			(end -0.120396 0.3048)
			(stroke
				(width 0.1)
				(type default)
			)
			(layer "B.Fab")
		)
		(fp_line
			(start -0.67945 -0.3048)
			(end -0.67945 0.3048)
			(stroke
				(width 0.1)
				(type default)
			)
			(layer "B.Fab")
		)
		(pad "1" smd circle
			(at 0.40005 0)
			(size 0 0)
			(layers "B.Cu" "B.Mask" "B.Paste")
			(net "PWRGD_PSU_AC_PWROK")
		)
		(pad "2" smd circle
			(at -0.40005 0)
			(size 0 0)
			(layers "B.Cu" "B.Mask" "B.Paste")
			(net "PWRGD_DSW_PWROK_R3")
		)
	)
	(footprint ""
		(layer "B.Cu")
		(at 24.003 -18.034 90)
		(property "Reference" "R419"
			(at 0 0 90)
			(layer "B.SilkS")
			(hide yes)
			(effects
				(font
					(size 1.27 1.27)
				)
				(justify mirror)
			)
		)
		(property "Value" ""
			(at 0 0 90)
			(layer "B.Fab")
			(effects
				(font
					(size 1.27 1.27)
				)
				(justify mirror)
			)
		)
		(duplicate_pad_numbers_are_jumpers no)
		(fp_line
			(start 0.7874 -0.4064)
			(end -0.7874 -0.4064)
			(stroke
				(width 0.1524)
				(type default)
			)
			(layer "B.SilkS")
		)
		(fp_line
			(start -0.7874 -0.4064)
			(end -0.7874 0.4064)
			(stroke
				(width 0.1524)
				(type default)
			)
			(layer "B.SilkS")
		)
		(fp_line
			(start 0.7874 0.4064)
			(end 0.7874 -0.4064)
			(stroke
				(width 0.1524)
				(type default)
			)
			(layer "B.SilkS")
		)
		(fp_line
			(start -0.7874 0.4064)
			(end 0.7874 0.4064)
			(stroke
				(width 0.1524)
				(type default)
			)
			(layer "B.SilkS")
		)
		(fp_line
			(start 0.67945 -0.305054)
			(end 0.12065 -0.305054)
			(stroke
				(width 0.1)
				(type default)
			)
			(layer "B.Fab")
		)
		(fp_line
			(start 0.12065 -0.305054)
			(end 0.12065 -0.2794)
			(stroke
				(width 0.1)
				(type default)
			)
			(layer "B.Fab")
		)
		(fp_line
			(start -0.12065 -0.3048)
			(end -0.67945 -0.3048)
			(stroke
				(width 0.1)
				(type default)
			)
			(layer "B.Fab")
		)
		(fp_line
			(start -0.67945 -0.3048)
			(end -0.67945 0.3048)
			(stroke
				(width 0.1)
				(type default)
			)
			(layer "B.Fab")
		)
		(fp_line
			(start 0.12065 -0.2794)
			(end -0.12065 -0.2794)
			(stroke
				(width 0.1)
				(type default)
			)
			(layer "B.Fab")
		)
		(fp_line
			(start -0.12065 -0.2794)
			(end -0.12065 -0.3048)
			(stroke
				(width 0.1)
				(type default)
			)
			(layer "B.Fab")
		)
		(fp_line
			(start 0.12065 0.2794)
			(end 0.12065 0.3048)
			(stroke
				(width 0.1)
				(type default)
			)
			(layer "B.Fab")
		)
		(fp_line
			(start -0.120396 0.2794)
			(end 0.12065 0.2794)
			(stroke
				(width 0.1)
				(type default)
			)
			(layer "B.Fab")
		)
		(fp_line
			(start 0.67945 0.3048)
			(end 0.67945 -0.305054)
			(stroke
				(width 0.1)
				(type default)
			)
			(layer "B.Fab")
		)
		(fp_line
			(start 0.12065 0.3048)
			(end 0.67945 0.3048)
			(stroke
				(width 0.1)
				(type default)
			)
			(layer "B.Fab")
		)
		(fp_line
			(start -0.120396 0.3048)
			(end -0.120396 0.2794)
			(stroke
				(width 0.1)
				(type default)
			)
			(layer "B.Fab")
		)
		(fp_line
			(start -0.67945 0.3048)
			(end -0.120396 0.3048)
			(stroke
				(width 0.1)
				(type default)
			)
			(layer "B.Fab")
		)
		(pad "1" smd circle
			(at 0.40005 0 270)
			(size 0 0)
			(layers "B.Cu" "B.Mask" "B.Paste")
			(net "TMC75_A2")
		)
		(pad "2" smd circle
			(at -0.40005 0 270)
			(size 0 0)
			(layers "B.Cu" "B.Mask" "B.Paste")
			(net "GND")
		)
	)
	(footprint ""
		(layer "B.Cu")
		(at 80.018636 -47.846488)
		(property "Reference" "C222"
			(at 0 0 0)
			(layer "B.SilkS")
			(hide yes)
			(effects
				(font
					(size 1.27 1.27)
				)
				(justify mirror)
			)
		)
		(property "Value" ""
			(at 0 0 0)
			(layer "B.Fab")
			(effects
				(font
					(size 1.27 1.27)
				)
				(justify mirror)
			)
		)
		(duplicate_pad_numbers_are_jumpers no)
		(fp_line
			(start -0.7874 -0.4064)
			(end -0.7874 0.4064)
			(stroke
				(width 0.1524)
				(type default)
			)
			(layer "B.SilkS")
		)
		(fp_line
			(start -0.7874 0.4064)
			(end 0.7874 0.4064)
			(stroke
				(width 0.1524)
				(type default)
			)
			(layer "B.SilkS")
		)
		(fp_line
			(start 0.7874 -0.4064)
			(end -0.7874 -0.4064)
			(stroke
				(width 0.1524)
				(type default)
			)
			(layer "B.SilkS")
		)
		(fp_line
			(start 0.7874 0.4064)
			(end 0.7874 -0.4064)
			(stroke
				(width 0.1524)
				(type default)
			)
			(layer "B.SilkS")
		)
		(fp_line
			(start -0.67945 -0.3048)
			(end -0.67945 0.3048)
			(stroke
				(width 0.1)
				(type default)
			)
			(layer "B.Fab")
		)
		(fp_line
			(start -0.67945 0.3048)
			(end -0.120396 0.3048)
			(stroke
				(width 0.1)
				(type default)
			)
			(layer "B.Fab")
		)
		(fp_line
			(start -0.12065 -0.3048)
			(end -0.67945 -0.3048)
			(stroke
				(width 0.1)
				(type default)
			)
			(layer "B.Fab")
		)
		(fp_line
			(start -0.12065 -0.2794)
			(end -0.12065 -0.3048)
			(stroke
				(width 0.1)
				(type default)
			)
			(layer "B.Fab")
		)
		(fp_line
			(start -0.120396 0.2794)
			(end 0.12065 0.2794)
			(stroke
				(width 0.1)
				(type default)
			)
			(layer "B.Fab")
		)
		(fp_line
			(start -0.120396 0.3048)
			(end -0.120396 0.2794)
			(stroke
				(width 0.1)
				(type default)
			)
			(layer "B.Fab")
		)
		(fp_line
			(start 0.12065 -0.305054)
			(end 0.12065 -0.2794)
			(stroke
				(width 0.1)
				(type default)
			)
			(layer "B.Fab")
		)
		(fp_line
			(start 0.12065 -0.2794)
			(end -0.12065 -0.2794)
			(stroke
				(width 0.1)
				(type default)
			)
			(layer "B.Fab")
		)
		(fp_line
			(start 0.12065 0.2794)
			(end 0.12065 0.3048)
			(stroke
				(width 0.1)
				(type default)
			)
			(layer "B.Fab")
		)
		(fp_line
			(start 0.12065 0.3048)
			(end 0.67945 0.3048)
			(stroke
				(width 0.1)
				(type default)
			)
			(layer "B.Fab")
		)
		(fp_line
			(start 0.67945 -0.305054)
			(end 0.12065 -0.305054)
			(stroke
				(width 0.1)
				(type default)
			)
			(layer "B.Fab")
		)
		(fp_line
			(start 0.67945 0.3048)
			(end 0.67945 -0.305054)
			(stroke
				(width 0.1)
				(type default)
			)
			(layer "B.Fab")
		)
		(pad "1" smd circle
			(at 0.40005 0 180)
			(size 0 0)
			(layers "B.Cu" "B.Mask" "B.Paste")
			(net "P1V2_AUX")
		)
		(pad "2" smd circle
			(at -0.40005 0 180)
			(size 0 0)
			(layers "B.Cu" "B.Mask" "B.Paste")
			(net "GND")
		)
	)
	(footprint ""
		(layer "B.Cu")
		(at 27.305 -101.981 90)
		(property "Reference" "L19"
			(at 0 0 90)
			(layer "B.SilkS")
			(hide yes)
			(effects
				(font
					(size 1.27 1.27)
				)
				(justify mirror)
			)
		)
		(property "Value" ""
			(at 0 0 90)
			(layer "B.Fab")
			(effects
				(font
					(size 1.27 1.27)
				)
				(justify mirror)
			)
		)
		(duplicate_pad_numbers_are_jumpers no)
		(fp_line
			(start 1.27 -0.5842)
			(end -1.27 -0.5842)
			(stroke
				(width 0.1524)
				(type default)
			)
			(layer "B.SilkS")
		)
		(fp_line
			(start 1.27 -0.5588)
			(end 1.27 -0.5842)
			(stroke
				(width 0.1524)
				(type default)
			)
			(layer "B.SilkS")
		)
		(fp_line
			(start 1.27 0.5842)
			(end 1.27 -0.5842)
			(stroke
				(width 0.1524)
				(type default)
			)
			(layer "B.SilkS")
		)
		(fp_line
			(start 0.127 0.5842)
			(end 0.127 -0.5842)
			(stroke
				(width 0.1524)
				(type default)
			)
			(layer "B.SilkS")
		)
		(fp_line
			(start -0.127 0.5842)
			(end -0.127 -0.5842)
			(stroke
				(width 0.1524)
				(type default)
			)
			(layer "B.SilkS")
		)
		(fp_line
			(start -1.27 0.5842)
			(end -1.27 -0.5842)
			(stroke
				(width 0.1524)
				(type default)
			)
			(layer "B.SilkS")
		)
		(fp_line
			(start -1.27 0.5842)
			(end 1.27 0.5842)
			(stroke
				(width 0.1524)
				(type default)
			)
			(layer "B.SilkS")
		)
		(fp_line
			(start 0.9144 -0.508)
			(end -0.9144 -0.508)
			(stroke
				(width 0.1)
				(type default)
			)
			(layer "B.Fab")
		)
		(fp_line
			(start -0.9144 -0.508)
			(end -0.914654 -0.406654)
			(stroke
				(width 0.1)
				(type default)
			)
			(layer "B.Fab")
		)
		(fp_line
			(start 1.194308 -0.406654)
			(end 0.914654 -0.406654)
			(stroke
				(width 0.1)
				(type default)
			)
			(layer "B.Fab")
		)
		(fp_line
			(start 0.914654 -0.406654)
			(end 0.9144 -0.508)
			(stroke
				(width 0.1)
				(type default)
			)
			(layer "B.Fab")
		)
		(fp_line
			(start -0.914654 -0.406654)
			(end -1.193546 -0.406654)
			(stroke
				(width 0.1)
				(type default)
			)
			(layer "B.Fab")
		)
		(fp_line
			(start -1.193546 -0.406654)
			(end -1.1938 0.4064)
			(stroke
				(width 0.1)
				(type default)
			)
			(layer "B.Fab")
		)
		(fp_line
			(start -0.9144 0.4064)
			(end -0.9144 0.508)
			(stroke
				(width 0.1)
				(type default)
			)
			(layer "B.Fab")
		)
		(fp_line
			(start -1.1938 0.4064)
			(end -0.9144 0.4064)
			(stroke
				(width 0.1)
				(type default)
			)
			(layer "B.Fab")
		)
		(fp_line
			(start 1.194308 0.406654)
			(end 1.194308 -0.406654)
			(stroke
				(width 0.1)
				(type default)
			)
			(layer "B.Fab")
		)
		(fp_line
			(start 0.914654 0.406654)
			(end 1.194308 0.406654)
			(stroke
				(width 0.1)
				(type default)
			)
			(layer "B.Fab")
		)
		(fp_line
			(start 0.9144 0.508)
			(end 0.914654 0.406654)
			(stroke
				(width 0.1)
				(type default)
			)
			(layer "B.Fab")
		)
		(fp_line
			(start -0.9144 0.508)
			(end 0.9144 0.508)
			(stroke
				(width 0.1)
				(type default)
			)
			(layer "B.Fab")
		)
		(pad "1" smd rect
			(at 0.7366 0)
			(size 0.7112 0.8128)
			(layers "B.Cu" "B.Mask" "B.Paste")
			(net "P3V3_AUX")
		)
		(pad "2" smd rect
			(at -0.7366 0)
			(size 0.7112 0.8128)
			(layers "B.Cu" "B.Mask" "B.Paste")
			(net "PVCCA_AUX_PLD")
		)
	)
)
